(kicad_pcb
	(version 20260206)
	(generator "pcbnew")
	(generator_version "10.0")
	(general
		(thickness 1.6)
		(legacy_teardrops no)
	)
	(paper "A4")
	(title_block
		(title "04192023_DAF0TMB3IC0_F0TG_MB_C_brd_V02_OCP.brd")
		(comment 1 "Grand Teton / footprint 3955 of 8354 (U25), pads 5777-5885 of 6102")
	)
	(layers
		(0 "F.Cu" signal "TOP")
		(4 "In1.Cu" signal "GND")
		(6 "In2.Cu" signal "IN1")
		(8 "In3.Cu" signal "GND1")
		(10 "In4.Cu" signal "IN2")
		(12 "In5.Cu" signal "GND2")
		(14 "In6.Cu" signal "IN3")
		(16 "In7.Cu" signal "GND3")
		(18 "In8.Cu" signal "VCC")
		(20 "In9.Cu" signal "VCC1")
		(22 "In10.Cu" signal "GND4")
		(24 "In11.Cu" signal "IN4")
		(26 "In12.Cu" signal "GND5")
		(28 "In13.Cu" signal "IN5")
		(30 "In14.Cu" signal "GND6")
		(32 "In15.Cu" signal "IN6")
		(34 "In16.Cu" signal "GND7")
		(2 "B.Cu" signal "BOTTOM")
		(9 "F.Adhes" user "F.Adhesive")
		(11 "B.Adhes" user "B.Adhesive")
		(13 "F.Paste" user "Package Geometry/Pastemask Top")
		(15 "B.Paste" user "Package Geometry/Pastemask Bottom")
		(5 "F.SilkS" user "Ref Des/Silkscreen Top")
		(7 "B.SilkS" user "Ref Des/Silkscreen Bottom")
		(1 "F.Mask" user "Board Geometry/Soldermask Top")
		(3 "B.Mask" user "Board Geometry/Soldermask Bottom")
		(17 "Dwgs.User" user "User.Drawings")
		(19 "Cmts.User" user "User.Comments")
		(21 "Eco1.User" user "User.Eco1")
		(23 "Eco2.User" user "User.Eco2")
		(25 "Edge.Cuts" user "Board Geometry/Outline")
		(27 "Margin" user)
		(31 "F.CrtYd" user "Package Geometry/Place Bound Top")
		(29 "B.CrtYd" user "Package Geometry/Place Bound Bottom")
		(35 "F.Fab" user "Ref Des/Assembly Top")
		(33 "B.Fab" user "Ref Des/Assembly Bottom")
	)
	(footprint ""
		(layer "F.Cu")
		(at 359.867962 -258.880102 180)
		(property "Reference" "U25"
			(at -45.78477 -62.086744 0)
			(unlocked yes)
			(layer "F.SilkS")
			(effects
				(font
					(size 0.7874 0.5842)
					(thickness 0.1524)
				)
			)
		)
		(property "Value" ""
			(at 0 0 180)
			(layer "F.Fab")
			(effects
				(font
					(size 1.27 1.27)
				)
			)
		)
		(duplicate_pad_numbers_are_jumpers no)
		(pad "T36" smd circle
			(at -1.729994 -24.660098 180)
			(size 0.450088 0.450088)
			(layers "F.Cu" "F.Mask" "F.Paste")
			(net "P5E_CPU0_G3_TX_DN<14>")
		)
		(pad "T37" smd circle
			(at -0.78994 -24.660098 180)
			(size 0.450088 0.450088)
			(layers "F.Cu" "F.Mask" "F.Paste")
			(net "GND")
		)
		(pad "T39" smd circle
			(at 1.089914 -24.660098 180)
			(size 0.450088 0.450088)
			(layers "F.Cu" "F.Mask" "F.Paste")
			(net "GND")
		)
		(pad "T40" smd circle
			(at 2.029968 -24.660098 180)
			(size 0.450088 0.450088)
			(layers "F.Cu" "F.Mask" "F.Paste")
			(net "GMI_CPU1_G3_CPU0_G1_TX_DN<1>")
		)
		(pad "T41" smd circle
			(at 2.970022 -24.660098 180)
			(size 0.450088 0.450088)
			(layers "F.Cu" "F.Mask" "F.Paste")
			(net "GMI_CPU1_G3_CPU0_G1_TX_DP<1>")
		)
		(pad "T42" smd circle
			(at 3.910076 -24.660098 180)
			(size 0.450088 0.450088)
			(layers "F.Cu" "F.Mask" "F.Paste")
			(net "GND")
		)
		(pad "T43" smd circle
			(at 4.849876 -24.660098 180)
			(size 0.450088 0.450088)
			(layers "F.Cu" "F.Mask" "F.Paste")
			(net "PVDDCR_CPU0_P0")
		)
		(pad "T44" smd circle
			(at 5.78993 -24.660098 180)
			(size 0.450088 0.450088)
			(layers "F.Cu" "F.Mask" "F.Paste")
			(net "PVDDCR_CPU0_P0")
		)
		(pad "T45" smd circle
			(at 6.729984 -24.660098 180)
			(size 0.450088 0.450088)
			(layers "F.Cu" "F.Mask" "F.Paste")
			(net "GND")
		)
		(pad "T46" smd circle
			(at 7.670038 -24.660098 180)
			(size 0.450088 0.450088)
			(layers "F.Cu" "F.Mask" "F.Paste")
			(net "PVDDCR_CPU0_P0")
		)
		(pad "T47" smd circle
			(at 8.610092 -24.660098 180)
			(size 0.450088 0.450088)
			(layers "F.Cu" "F.Mask" "F.Paste")
			(net "PVDDCR_CPU0_P0")
		)
		(pad "T48" smd circle
			(at 9.549892 -24.660098 180)
			(size 0.450088 0.450088)
			(layers "F.Cu" "F.Mask" "F.Paste")
			(net "GND")
		)
		(pad "T49" smd circle
			(at 10.489946 -24.660098 180)
			(size 0.450088 0.450088)
			(layers "F.Cu" "F.Mask" "F.Paste")
			(net "PVDDCR_CPU0_P0")
		)
		(pad "T50" smd circle
			(at 11.43 -24.660098 180)
			(size 0.450088 0.450088)
			(layers "F.Cu" "F.Mask" "F.Paste")
			(net "PVDDCR_CPU0_P0")
		)
		(pad "T51" smd circle
			(at 12.370054 -24.660098 180)
			(size 0.450088 0.450088)
			(layers "F.Cu" "F.Mask" "F.Paste")
			(net "GND")
		)
		(pad "T52" smd circle
			(at 13.310108 -24.660098 180)
			(size 0.450088 0.450088)
			(layers "F.Cu" "F.Mask" "F.Paste")
			(net "PVDDCR_CPU0_P0")
		)
		(pad "T53" smd circle
			(at 14.249908 -24.660098 180)
			(size 0.450088 0.450088)
			(layers "F.Cu" "F.Mask" "F.Paste")
			(net "PVDDCR_CPU0_P0")
		)
		(pad "T54" smd circle
			(at 15.189962 -24.660098 180)
			(size 0.450088 0.450088)
			(layers "F.Cu" "F.Mask" "F.Paste")
			(net "GND")
		)
		(pad "T55" smd circle
			(at 16.130016 -24.660098 180)
			(size 0.450088 0.450088)
			(layers "F.Cu" "F.Mask" "F.Paste")
			(net "M_C_CPU0_SA_DQ<13>")
		)
		(pad "T56" smd circle
			(at 17.07007 -24.660098 180)
			(size 0.450088 0.450088)
			(layers "F.Cu" "F.Mask" "F.Paste")
			(net "M_C_CPU0_SA_DQ<14>")
		)
		(pad "T57" smd circle
			(at 18.010124 -24.660098 180)
			(size 0.450088 0.450088)
			(layers "F.Cu" "F.Mask" "F.Paste")
			(net "GND")
		)
		(pad "T58" smd circle
			(at 18.949924 -24.660098 180)
			(size 0.450088 0.450088)
			(layers "F.Cu" "F.Mask" "F.Paste")
			(net "M_D_CPU0_SA_DQ<13>")
		)
		(pad "T59" smd circle
			(at 19.889978 -24.660098 180)
			(size 0.450088 0.450088)
			(layers "F.Cu" "F.Mask" "F.Paste")
			(net "GND")
		)
		(pad "T60" smd circle
			(at 20.830032 -24.660098 180)
			(size 0.450088 0.450088)
			(layers "F.Cu" "F.Mask" "F.Paste")
			(net "M_D_CPU0_SA_DQ<14>")
		)
		(pad "T61" smd circle
			(at 21.770086 -24.660098 180)
			(size 0.450088 0.450088)
			(layers "F.Cu" "F.Mask" "F.Paste")
			(net "GND")
		)
		(pad "T62" smd circle
			(at 22.709886 -24.660098 180)
			(size 0.450088 0.450088)
			(layers "F.Cu" "F.Mask" "F.Paste")
			(net "M_B_CPU0_SA_DQ<13>")
		)
		(pad "T63" smd circle
			(at 23.64994 -24.660098 180)
			(size 0.450088 0.450088)
			(layers "F.Cu" "F.Mask" "F.Paste")
			(net "M_B_CPU0_SA_DQ<14>")
		)
		(pad "T64" smd circle
			(at 24.589994 -24.660098 180)
			(size 0.450088 0.450088)
			(layers "F.Cu" "F.Mask" "F.Paste")
			(net "GND")
		)
		(pad "T65" smd circle
			(at 25.530048 -24.660098 180)
			(size 0.450088 0.450088)
			(layers "F.Cu" "F.Mask" "F.Paste")
			(net "M_F_CPU0_SA_DQ<13>")
		)
		(pad "T66" smd circle
			(at 26.470102 -24.660098 180)
			(size 0.450088 0.450088)
			(layers "F.Cu" "F.Mask" "F.Paste")
			(net "GND")
		)
		(pad "T67" smd circle
			(at 27.409902 -24.660098 180)
			(size 0.450088 0.450088)
			(layers "F.Cu" "F.Mask" "F.Paste")
			(net "M_F_CPU0_SA_DQ<14>")
		)
		(pad "T68" smd circle
			(at 28.349956 -24.660098 180)
			(size 0.450088 0.450088)
			(layers "F.Cu" "F.Mask" "F.Paste")
			(net "GND")
		)
		(pad "T69" smd circle
			(at 29.29001 -24.660098 180)
			(size 0.450088 0.450088)
			(layers "F.Cu" "F.Mask" "F.Paste")
			(net "M_E_CPU0_SA_DQ<13>")
		)
		(pad "T70" smd circle
			(at 30.230064 -24.660098 180)
			(size 0.450088 0.450088)
			(layers "F.Cu" "F.Mask" "F.Paste")
			(net "M_E_CPU0_SA_DQ<14>")
		)
		(pad "T71" smd circle
			(at 31.170118 -24.660098 180)
			(size 0.450088 0.450088)
			(layers "F.Cu" "F.Mask" "F.Paste")
			(net "GND")
		)
		(pad "T72" smd circle
			(at 32.109918 -24.660098 180)
			(size 0.450088 0.450088)
			(layers "F.Cu" "F.Mask" "F.Paste")
			(net "M_A_CPU0_SA_DQ<13>")
		)
		(pad "T73" smd circle
			(at 33.049972 -24.660098 180)
			(size 0.450088 0.450088)
			(layers "F.Cu" "F.Mask" "F.Paste")
			(net "GND")
		)
		(pad "T74" smd circle
			(at 33.990026 -24.660098 180)
			(size 0.450088 0.450088)
			(layers "F.Cu" "F.Mask" "F.Paste")
			(net "M_A_CPU0_SA_DQ<14>")
		)
		(pad "U1" smd circle
			(at -34.159952 -23.850092 180)
			(size 0.450088 0.450088)
			(layers "F.Cu" "F.Mask" "F.Paste")
			(net "GND")
		)
		(pad "U2" smd circle
			(at -33.219898 -23.850092 180)
			(size 0.450088 0.450088)
			(layers "F.Cu" "F.Mask" "F.Paste")
			(net "M_G_CPU0_SA_DQ<16>")
		)
		(pad "U3" smd circle
			(at -32.280098 -23.850092 180)
			(size 0.450088 0.450088)
			(layers "F.Cu" "F.Mask" "F.Paste")
			(net "M_G_CPU0_SA_DQ<15>")
		)
		(pad "U4" smd circle
			(at -31.340044 -23.850092 180)
			(size 0.450088 0.450088)
			(layers "F.Cu" "F.Mask" "F.Paste")
			(net "PVDDCR_SOC_P0")
		)
		(pad "U5" smd circle
			(at -30.39999 -23.850092 180)
			(size 0.450088 0.450088)
			(layers "F.Cu" "F.Mask" "F.Paste")
			(net "M_K_CPU0_SA_DQ<16>")
		)
		(pad "U6" smd circle
			(at -29.459936 -23.850092 180)
			(size 0.450088 0.450088)
			(layers "F.Cu" "F.Mask" "F.Paste")
			(net "GND")
		)
		(pad "U7" smd circle
			(at -28.519882 -23.850092 180)
			(size 0.450088 0.450088)
			(layers "F.Cu" "F.Mask" "F.Paste")
			(net "M_K_CPU0_SA_DQ<15>")
		)
		(pad "U8" smd circle
			(at -27.580082 -23.850092 180)
			(size 0.450088 0.450088)
			(layers "F.Cu" "F.Mask" "F.Paste")
			(net "GND")
		)
		(pad "U9" smd circle
			(at -26.640028 -23.850092 180)
			(size 0.450088 0.450088)
			(layers "F.Cu" "F.Mask" "F.Paste")
			(net "M_L_CPU0_SA_DQ<16>")
		)
		(pad "U10" smd circle
			(at -25.699974 -23.850092 180)
			(size 0.450088 0.450088)
			(layers "F.Cu" "F.Mask" "F.Paste")
			(net "M_L_CPU0_SA_DQ<15>")
		)
		(pad "U11" smd circle
			(at -24.75992 -23.850092 180)
			(size 0.450088 0.450088)
			(layers "F.Cu" "F.Mask" "F.Paste")
			(net "PVDDCR_SOC_P0")
		)
		(pad "U12" smd circle
			(at -23.82012 -23.850092 180)
			(size 0.450088 0.450088)
			(layers "F.Cu" "F.Mask" "F.Paste")
			(net "M_H_CPU0_SA_DQ<16>")
		)
		(pad "U13" smd circle
			(at -22.880066 -23.850092 180)
			(size 0.450088 0.450088)
			(layers "F.Cu" "F.Mask" "F.Paste")
			(net "GND")
		)
		(pad "U14" smd circle
			(at -21.940012 -23.850092 180)
			(size 0.450088 0.450088)
			(layers "F.Cu" "F.Mask" "F.Paste")
			(net "M_H_CPU0_SA_DQ<15>")
		)
		(pad "U15" smd circle
			(at -20.999958 -23.850092 180)
			(size 0.450088 0.450088)
			(layers "F.Cu" "F.Mask" "F.Paste")
			(net "GND")
		)
		(pad "U16" smd circle
			(at -20.059904 -23.850092 180)
			(size 0.450088 0.450088)
			(layers "F.Cu" "F.Mask" "F.Paste")
			(net "M_J_CPU0_SA_DQ<16>")
		)
		(pad "U17" smd circle
			(at -19.120104 -23.850092 180)
			(size 0.450088 0.450088)
			(layers "F.Cu" "F.Mask" "F.Paste")
			(net "M_J_CPU0_SA_DQ<15>")
		)
		(pad "U18" smd circle
			(at -18.18005 -23.850092 180)
			(size 0.450088 0.450088)
			(layers "F.Cu" "F.Mask" "F.Paste")
			(net "PVDDCR_SOC_P0")
		)
		(pad "U19" smd circle
			(at -17.239996 -23.850092 180)
			(size 0.450088 0.450088)
			(layers "F.Cu" "F.Mask" "F.Paste")
			(net "M_I_CPU0_SA_DQ<16>")
		)
		(pad "U20" smd circle
			(at -16.299942 -23.850092 180)
			(size 0.450088 0.450088)
			(layers "F.Cu" "F.Mask" "F.Paste")
			(net "GND")
		)
		(pad "U21" smd circle
			(at -15.359888 -23.850092 180)
			(size 0.450088 0.450088)
			(layers "F.Cu" "F.Mask" "F.Paste")
			(net "M_I_CPU0_SA_DQ<15>")
		)
		(pad "U22" smd circle
			(at -14.420088 -23.850092 180)
			(size 0.450088 0.450088)
			(layers "F.Cu" "F.Mask" "F.Paste")
			(net "GND")
		)
		(pad "U23" smd circle
			(at -13.480034 -23.850092 180)
			(size 0.450088 0.450088)
			(layers "F.Cu" "F.Mask" "F.Paste")
			(net "P5E_CPU0_G3_TX_DP<0>")
		)
		(pad "U24" smd circle
			(at -12.53998 -23.850092 180)
			(size 0.450088 0.450088)
			(layers "F.Cu" "F.Mask" "F.Paste")
			(net "P5E_CPU0_G3_TX_DN<0>")
		)
		(pad "U25" smd circle
			(at -11.599926 -23.850092 180)
			(size 0.450088 0.450088)
			(layers "F.Cu" "F.Mask" "F.Paste")
			(net "GND")
		)
		(pad "U26" smd circle
			(at -10.659872 -23.850092 180)
			(size 0.450088 0.450088)
			(layers "F.Cu" "F.Mask" "F.Paste")
			(net "P5E_CPU0_G3_TX_DP<3>")
		)
		(pad "U27" smd circle
			(at -9.720072 -23.850092 180)
			(size 0.450088 0.450088)
			(layers "F.Cu" "F.Mask" "F.Paste")
			(net "P5E_CPU0_G3_TX_DN<3>")
		)
		(pad "U28" smd circle
			(at -8.780018 -23.850092 180)
			(size 0.450088 0.450088)
			(layers "F.Cu" "F.Mask" "F.Paste")
			(net "GND")
		)
		(pad "U29" smd circle
			(at -7.839964 -23.850092 180)
			(size 0.450088 0.450088)
			(layers "F.Cu" "F.Mask" "F.Paste")
			(net "P5E_CPU0_G3_TX_DP<9>")
		)
		(pad "U30" smd circle
			(at -6.89991 -23.850092 180)
			(size 0.450088 0.450088)
			(layers "F.Cu" "F.Mask" "F.Paste")
			(net "P5E_CPU0_G3_TX_DN<9>")
		)
		(pad "U31" smd circle
			(at -5.96011 -23.850092 180)
			(size 0.450088 0.450088)
			(layers "F.Cu" "F.Mask" "F.Paste")
			(net "GND")
		)
		(pad "U32" smd circle
			(at -5.020056 -23.850092 180)
			(size 0.450088 0.450088)
			(layers "F.Cu" "F.Mask" "F.Paste")
			(net "P5E_CPU0_G3_TX_DP<12>")
		)
		(pad "U33" smd circle
			(at -4.080002 -23.850092 180)
			(size 0.450088 0.450088)
			(layers "F.Cu" "F.Mask" "F.Paste")
			(net "P5E_CPU0_G3_TX_DN<12>")
		)
		(pad "U34" smd circle
			(at -3.139948 -23.850092 180)
			(size 0.450088 0.450088)
			(layers "F.Cu" "F.Mask" "F.Paste")
			(net "GND")
		)
		(pad "U35" smd circle
			(at -2.199894 -23.850092 180)
			(size 0.450088 0.450088)
			(layers "F.Cu" "F.Mask" "F.Paste")
			(net "PVDDCR_CPU0_P0")
		)
		(pad "U36" smd circle
			(at -1.260094 -23.850092 180)
			(size 0.450088 0.450088)
			(layers "F.Cu" "F.Mask" "F.Paste")
			(net "PVDDCR_CPU0_P0")
		)
		(pad "U40" smd circle
			(at 1.560068 -23.850092 180)
			(size 0.450088 0.450088)
			(layers "F.Cu" "F.Mask" "F.Paste")
			(net "PVDDCR_CPU0_P0")
		)
		(pad "U41" smd circle
			(at 2.500122 -23.850092 180)
			(size 0.450088 0.450088)
			(layers "F.Cu" "F.Mask" "F.Paste")
			(net "PVDDCR_CPU0_P0")
		)
		(pad "U42" smd circle
			(at 3.439922 -23.850092 180)
			(size 0.450088 0.450088)
			(layers "F.Cu" "F.Mask" "F.Paste")
			(net "GND")
		)
		(pad "U43" smd circle
			(at 4.379976 -23.850092 180)
			(size 0.450088 0.450088)
			(layers "F.Cu" "F.Mask" "F.Paste")
			(net "GMI_CPU1_G3_CPU0_G1_TX_DN<3>")
		)
		(pad "U44" smd circle
			(at 5.32003 -23.850092 180)
			(size 0.450088 0.450088)
			(layers "F.Cu" "F.Mask" "F.Paste")
			(net "GMI_CPU1_G3_CPU0_G1_TX_DP<3>")
		)
		(pad "U45" smd circle
			(at 6.260084 -23.850092 180)
			(size 0.450088 0.450088)
			(layers "F.Cu" "F.Mask" "F.Paste")
			(net "GND")
		)
		(pad "U46" smd circle
			(at 7.199884 -23.850092 180)
			(size 0.450088 0.450088)
			(layers "F.Cu" "F.Mask" "F.Paste")
			(net "GMI_CPU1_G3_CPU0_G1_TX_DN<6>")
		)
		(pad "U47" smd circle
			(at 8.139938 -23.850092 180)
			(size 0.450088 0.450088)
			(layers "F.Cu" "F.Mask" "F.Paste")
			(net "GMI_CPU1_G3_CPU0_G1_TX_DP<6>")
		)
		(pad "U48" smd circle
			(at 9.079992 -23.850092 180)
			(size 0.450088 0.450088)
			(layers "F.Cu" "F.Mask" "F.Paste")
			(net "GND")
		)
		(pad "U49" smd circle
			(at 10.020046 -23.850092 180)
			(size 0.450088 0.450088)
			(layers "F.Cu" "F.Mask" "F.Paste")
			(net "GMI_CPU1_G3_CPU0_G1_TX_DN<12>")
		)
		(pad "U50" smd circle
			(at 10.9601 -23.850092 180)
			(size 0.450088 0.450088)
			(layers "F.Cu" "F.Mask" "F.Paste")
			(net "GMI_CPU1_G3_CPU0_G1_TX_DP<12>")
		)
		(pad "U51" smd circle
			(at 11.8999 -23.850092 180)
			(size 0.450088 0.450088)
			(layers "F.Cu" "F.Mask" "F.Paste")
			(net "GND")
		)
		(pad "U52" smd circle
			(at 12.839954 -23.850092 180)
			(size 0.450088 0.450088)
			(layers "F.Cu" "F.Mask" "F.Paste")
			(net "GMI_CPU1_G3_CPU0_G1_TX_DN<15>")
		)
		(pad "U53" smd circle
			(at 13.780008 -23.850092 180)
			(size 0.450088 0.450088)
			(layers "F.Cu" "F.Mask" "F.Paste")
			(net "GMI_CPU1_G3_CPU0_G1_TX_DP<15>")
		)
		(pad "U54" smd circle
			(at 14.720062 -23.850092 180)
			(size 0.450088 0.450088)
			(layers "F.Cu" "F.Mask" "F.Paste")
			(net "GND")
		)
		(pad "U55" smd circle
			(at 15.660116 -23.850092 180)
			(size 0.450088 0.450088)
			(layers "F.Cu" "F.Mask" "F.Paste")
			(net "M_C_CPU0_SA_DQ<15>")
		)
		(pad "U56" smd circle
			(at 16.599916 -23.850092 180)
			(size 0.450088 0.450088)
			(layers "F.Cu" "F.Mask" "F.Paste")
			(net "GND")
		)
		(pad "U57" smd circle
			(at 17.53997 -23.850092 180)
			(size 0.450088 0.450088)
			(layers "F.Cu" "F.Mask" "F.Paste")
			(net "M_C_CPU0_SA_DQ<16>")
		)
		(pad "U58" smd circle
			(at 18.480024 -23.850092 180)
			(size 0.450088 0.450088)
			(layers "F.Cu" "F.Mask" "F.Paste")
			(net "PVDDIO_P0")
		)
		(pad "U59" smd circle
			(at 19.420078 -23.850092 180)
			(size 0.450088 0.450088)
			(layers "F.Cu" "F.Mask" "F.Paste")
			(net "M_D_CPU0_SA_DQ<15>")
		)
		(pad "U60" smd circle
			(at 20.359878 -23.850092 180)
			(size 0.450088 0.450088)
			(layers "F.Cu" "F.Mask" "F.Paste")
			(net "M_D_CPU0_SA_DQ<16>")
		)
		(pad "U61" smd circle
			(at 21.299932 -23.850092 180)
			(size 0.450088 0.450088)
			(layers "F.Cu" "F.Mask" "F.Paste")
			(net "GND")
		)
		(pad "U62" smd circle
			(at 22.239986 -23.850092 180)
			(size 0.450088 0.450088)
			(layers "F.Cu" "F.Mask" "F.Paste")
			(net "M_B_CPU0_SA_DQ<15>")
		)
		(pad "U63" smd circle
			(at 23.18004 -23.850092 180)
			(size 0.450088 0.450088)
			(layers "F.Cu" "F.Mask" "F.Paste")
			(net "GND")
		)
		(pad "U64" smd circle
			(at 24.120094 -23.850092 180)
			(size 0.450088 0.450088)
			(layers "F.Cu" "F.Mask" "F.Paste")
			(net "M_B_CPU0_SA_DQ<16>")
		)
		(pad "U65" smd circle
			(at 25.059894 -23.850092 180)
			(size 0.450088 0.450088)
			(layers "F.Cu" "F.Mask" "F.Paste")
			(net "PVDDIO_P0")
		)
		(pad "U66" smd circle
			(at 25.999948 -23.850092 180)
			(size 0.450088 0.450088)
			(layers "F.Cu" "F.Mask" "F.Paste")
			(net "M_F_CPU0_SA_DQ<15>")
		)
		(pad "U67" smd circle
			(at 26.940002 -23.850092 180)
			(size 0.450088 0.450088)
			(layers "F.Cu" "F.Mask" "F.Paste")
			(net "M_F_CPU0_SA_DQ<16>")
		)
		(pad "U68" smd circle
			(at 27.880056 -23.850092 180)
			(size 0.450088 0.450088)
			(layers "F.Cu" "F.Mask" "F.Paste")
			(net "GND")
		)
		(pad "U69" smd circle
			(at 28.82011 -23.850092 180)
			(size 0.450088 0.450088)
			(layers "F.Cu" "F.Mask" "F.Paste")
			(net "M_E_CPU0_SA_DQ<15>")
		)
		(pad "U70" smd circle
			(at 29.75991 -23.850092 180)
			(size 0.450088 0.450088)
			(layers "F.Cu" "F.Mask" "F.Paste")
			(net "GND")
		)
		(pad "U71" smd circle
			(at 30.699964 -23.850092 180)
			(size 0.450088 0.450088)
			(layers "F.Cu" "F.Mask" "F.Paste")
			(net "M_E_CPU0_SA_DQ<16>")
		)
		(pad "U72" smd circle
			(at 31.640018 -23.850092 180)
			(size 0.450088 0.450088)
			(layers "F.Cu" "F.Mask" "F.Paste")
			(net "PVDDIO_P0")
		)
		(pad "U73" smd circle
			(at 32.580072 -23.850092 180)
			(size 0.450088 0.450088)
			(layers "F.Cu" "F.Mask" "F.Paste")
			(net "M_A_CPU0_SA_DQ<15>")
		)
		(pad "U74" smd circle
			(at 33.519872 -23.850092 180)
			(size 0.450088 0.450088)
			(layers "F.Cu" "F.Mask" "F.Paste")
			(net "M_A_CPU0_SA_DQ<16>")
		)
	)
)
